# TIMECARD (Time Appliance Project (Time Card)) — schematic netlist excerpt (pin names and nets, part order shuffled) for the footprints in the layout excerpt that follows; sources: Cadence DE-HDL packaged netlist, KiCad conversion of R4006-B0001-02_R01.brd

R385  RESISTOR  33OHM 1%  pkg SMC_0402R_H016  page 26 : \1\ = SMA1_LED_BLUE_N ; \2\ = UNNAMED_14_LED4PV14_I265_1

(kicad_pcb
	(version 20260206)
	(generator "pcbnew")
	(generator_version "10.0")
	(general
		(thickness 1.6)
		(legacy_teardrops no)
	)
	(paper "A4")
	(title_block
		(title "timecard-production-celestica-r4006 — R4006-B0001-02_R01.brd")
		(comment 1 "Time Appliance Project (Time Card) / footprints 347-347 of 1113")
	)
	(layers
		(0 "F.Cu" signal "TOP")
		(4 "In1.Cu" signal "L02_GND1")
		(6 "In2.Cu" signal "L03_SIG1")
		(8 "In3.Cu" signal "L04_GND2")
		(10 "In4.Cu" signal "L05_VCC1")
		(12 "In5.Cu" signal "L06_VCC2")
		(14 "In6.Cu" signal "L07_GND3")
		(16 "In7.Cu" signal "L08_SIG2")
		(18 "In8.Cu" signal "L09_GND4")
		(2 "B.Cu" signal "BOTTOM")
		(9 "F.Adhes" user "F.Adhesive")
		(11 "B.Adhes" user "B.Adhesive")
		(13 "F.Paste" user "Package Geometry/Pastemask Top")
		(15 "B.Paste" user "Package Geometry/Pastemask Bottom")
		(5 "F.SilkS" user "Ref Des/Silkscreen Top")
		(7 "B.SilkS" user "Ref Des/Silkscreen Bottom")
		(1 "F.Mask" user "Board Geometry/Soldermask Top")
		(3 "B.Mask" user "Board Geometry/Soldermask Bottom")
		(17 "Dwgs.User" user "User.Drawings")
		(19 "Cmts.User" user "User.Comments")
		(21 "Eco1.User" user "User.Eco1")
		(23 "Eco2.User" user "User.Eco2")
		(25 "Edge.Cuts" user "Board Geometry/Outline")
		(27 "Margin" user)
		(31 "F.CrtYd" user "Package Geometry/Place Bound Top")
		(29 "B.CrtYd" user "Package Geometry/Place Bound Bottom")
		(35 "F.Fab" user "Ref Des/Assembly Top")
		(33 "B.Fab" user "Ref Des/Assembly Bottom")
	)
	(footprint ""
		(layer "F.Cu")
		(at 4.8514 -39.318692 90)
		(property "Reference" "R385"
			(at 2.337308 0.20955 90)
			(unlocked yes)
			(layer "F.SilkS")
			(effects
				(font
					(size 0.635 0.4064)
					(thickness 0.1524)
				)
			)
		)
		(property "Value" "VAL*"
			(at 0.02032 2.13233 90)
			(unlocked yes)
			(layer "F.Fab")
			(hide yes)
			(effects
				(font
					(size 0.7874 0.5842)
					(thickness 0.1524)
				)
			)
		)
		(property "Tolerance" "TOL*"
			(at 0.044704 3.05435 90)
			(unlocked yes)
			(layer "Cmts.User")
			(hide yes)
			(effects
				(font
					(size 0.7874 0.5842)
					(thickness 0.1524)
				)
			)
		)
		(property "User Part Number" "PARTNUM*"
			(at 0.02032 4.024884 90)
			(unlocked yes)
			(layer "Cmts.User")
			(hide yes)
			(effects
				(font
					(size 0.7874 0.5842)
					(thickness 0.1524)
				)
			)
		)
		(property "Device Type" "RESISTOR-G155-133R0-01,33OHM,1%"
			(at 0.008382 1.210564 90)
			(unlocked yes)
			(layer "F.Fab")
			(hide yes)
			(effects
				(font
					(size 0.7874 0.5842)
					(thickness 0.1524)
				)
			)
		)
		(duplicate_pad_numbers_are_jumpers no)
		(fp_line
			(start 1.143 -0.5588)
			(end -1.143 -0.5588)
			(stroke
				(width 0.1)
				(type default)
			)
			(layer "F.SilkS")
		)
		(fp_line
			(start -1.143 -0.5588)
			(end -1.143 0.5588)
			(stroke
				(width 0.1)
				(type default)
			)
			(layer "F.SilkS")
		)
		(fp_line
			(start 1.143 0.5588)
			(end 1.143 -0.5588)
			(stroke
				(width 0.1)
				(type default)
			)
			(layer "F.SilkS")
		)
		(fp_line
			(start -1.143 0.5588)
			(end 1.143 0.5588)
			(stroke
				(width 0.1)
				(type default)
			)
			(layer "F.SilkS")
		)
		(fp_rect
			(start -1.143 -0.5588)
			(end 1.143 0.5588)
			(stroke
				(width 0)
				(type default)
			)
			(fill no)
			(layer "F.CrtYd")
		)
		(fp_line
			(start 0.508 -0.3048)
			(end -0.508 -0.3048)
			(stroke
				(width 0.1)
				(type default)
			)
			(layer "F.Fab")
		)
		(fp_line
			(start -0.508 -0.3048)
			(end -0.508 0.3048)
			(stroke
				(width 0.1)
				(type default)
			)
			(layer "F.Fab")
		)
		(fp_line
			(start 0.508 0.3048)
			(end 0.508 -0.3048)
			(stroke
				(width 0.1)
				(type default)
			)
			(layer "F.Fab")
		)
		(fp_line
			(start -0.508 0.3048)
			(end 0.508 0.3048)
			(stroke
				(width 0.1)
				(type default)
			)
			(layer "F.Fab")
		)
		(pad "1" smd rect
			(at -0.5334 0 90)
			(size 0.7112 0.6096)
			(layers "F.Cu" "F.Mask" "F.Paste")
			(net "SMA1_LED_BLUE_N")
		)
		(pad "2" smd rect
			(at 0.5334 0 90)
			(size 0.7112 0.6096)
			(layers "F.Cu" "F.Mask" "F.Paste")
			(net "UNNAMED_14_LED4PV14_I265_1")
		)
		(zone
			(layer "F.Cu")
			(hatch none 0.5)
			(connect_pads
				(clearance 0)
			)
			(min_thickness 0.25)
			(keepout
				(tracks not_allowed)
				(vias allowed)
				(pads allowed)
				(copperpour not_allowed)
				(footprints allowed)
			)
			(placement
				(enabled no)
				(sheetname "")
			)
			(fill
				(thermal_gap 0.5)
				(thermal_bridge_width 0.5)
				(island_removal_mode 0)
			)
			(polygon
				(pts
					(xy 4.5466 -39.242492) (xy 5.1562 -39.242492) (xy 5.1562 -39.394892) (xy 4.5466 -39.394892)
				)
			)
		)
		(zone
			(layer "F.Cu")
			(hatch none 0.5)
			(connect_pads
				(clearance 0)
			)
			(min_thickness 0.25)
			(keepout
				(tracks allowed)
				(vias not_allowed)
				(pads allowed)
				(copperpour not_allowed)
				(footprints allowed)
			)
			(placement
				(enabled no)
				(sheetname "")
			)
			(fill
				(thermal_gap 0.5)
				(thermal_bridge_width 0.5)
				(island_removal_mode 0)
			)
			(polygon
				(pts
					(xy 4.5466 -39.242492) (xy 5.1562 -39.242492) (xy 5.1562 -39.394892) (xy 4.5466 -39.394892)
				)
			)
		)
	)
)
